# S9S_MB_2U (Grand Teton) — schematic netlist excerpt (pin names and nets, part order shuffled) for the footprints in the layout excerpt that follows; sources: Cadence DE-HDL packaged netlist, KiCad conversion of 03242023_DA0F0TMBIJ0_F0T_Motherboard_J_brd_V01_OCP.brd

C1391  Q_CAP  47UF 2.5V 20% X6S  pkg C0603  page 78 : A = PVNN_MAIN_CPU1 ; B = GND
R895  Q_RES  33.2 1% CHIP  pkg 0402LF  page 114 : A = PWRGD_CHB_CPU1_DIMM1 ; B = PWRGD_FAIL_CPU1_AB

(kicad_pcb
	(version 20260206)
	(generator "pcbnew")
	(generator_version "10.0")
	(general
		(thickness 1.6)
		(legacy_teardrops no)
	)
	(paper "A4")
	(title_block
		(title "03242023_DA0F0TMBIJ0_F0T_Motherboard_J_brd_V01_OCP.brd")
		(comment 1 "Grand Teton / footprints 4686-4687 of 6105")
	)
	(layers
		(0 "F.Cu" signal "TOP")
		(4 "In1.Cu" signal "GND")
		(6 "In2.Cu" signal "IN1")
		(8 "In3.Cu" signal "GND1")
		(10 "In4.Cu" signal "IN2")
		(12 "In5.Cu" signal "GND2")
		(14 "In6.Cu" signal "IN3")
		(16 "In7.Cu" signal "GND3")
		(18 "In8.Cu" signal "VCC")
		(20 "In9.Cu" signal "VCC1")
		(22 "In10.Cu" signal "GND4")
		(24 "In11.Cu" signal "IN4")
		(26 "In12.Cu" signal "GND5")
		(28 "In13.Cu" signal "IN5")
		(30 "In14.Cu" signal "GND6")
		(32 "In15.Cu" signal "IN6")
		(34 "In16.Cu" signal "GND7")
		(2 "B.Cu" signal "BOTTOM")
		(9 "F.Adhes" user "F.Adhesive")
		(11 "B.Adhes" user "B.Adhesive")
		(13 "F.Paste" user "Package Geometry/Pastemask Top")
		(15 "B.Paste" user "Package Geometry/Pastemask Bottom")
		(5 "F.SilkS" user "Ref Des/Silkscreen Top")
		(7 "B.SilkS" user "Ref Des/Silkscreen Bottom")
		(1 "F.Mask" user "Board Geometry/Soldermask Top")
		(3 "B.Mask" user "Board Geometry/Soldermask Bottom")
		(17 "Dwgs.User" user "User.Drawings")
		(19 "Cmts.User" user "User.Comments")
		(21 "Eco1.User" user "User.Eco1")
		(23 "Eco2.User" user "User.Eco2")
		(25 "Edge.Cuts" user "Board Geometry/Outline")
		(27 "Margin" user)
		(31 "F.CrtYd" user "Package Geometry/Place Bound Top")
		(29 "B.CrtYd" user "Package Geometry/Place Bound Bottom")
		(35 "F.Fab" user "Ref Des/Assembly Top")
		(33 "B.Fab" user "Ref Des/Assembly Bottom")
	)
	(footprint ""
		(layer "B.Cu")
		(at 42.392346 -319.268856 180)
		(property "Reference" "R895"
			(at 0 0 0)
			(layer "B.SilkS")
			(hide yes)
			(effects
				(font
					(size 1.27 1.27)
				)
				(justify mirror)
			)
		)
		(property "Value" ""
			(at 0 0 0)
			(layer "B.Fab")
			(effects
				(font
					(size 1.27 1.27)
				)
				(justify mirror)
			)
		)
		(duplicate_pad_numbers_are_jumpers no)
		(fp_line
			(start 0.7874 0.4064)
			(end 0.7874 -0.4064)
			(stroke
				(width 0.1524)
				(type default)
			)
			(layer "B.SilkS")
		)
		(fp_line
			(start 0.7874 -0.4064)
			(end -0.7874 -0.4064)
			(stroke
				(width 0.1524)
				(type default)
			)
			(layer "B.SilkS")
		)
		(fp_line
			(start -0.7874 0.4064)
			(end 0.7874 0.4064)
			(stroke
				(width 0.1524)
				(type default)
			)
			(layer "B.SilkS")
		)
		(fp_line
			(start -0.7874 -0.4064)
			(end -0.7874 0.4064)
			(stroke
				(width 0.1524)
				(type default)
			)
			(layer "B.SilkS")
		)
		(fp_line
			(start 0.67945 0.3048)
			(end 0.67945 -0.305054)
			(stroke
				(width 0.1)
				(type default)
			)
			(layer "B.Fab")
		)
		(fp_line
			(start 0.67945 -0.305054)
			(end 0.12065 -0.305054)
			(stroke
				(width 0.1)
				(type default)
			)
			(layer "B.Fab")
		)
		(fp_line
			(start 0.12065 0.3048)
			(end 0.67945 0.3048)
			(stroke
				(width 0.1)
				(type default)
			)
			(layer "B.Fab")
		)
		(fp_line
			(start 0.12065 0.2794)
			(end 0.12065 0.3048)
			(stroke
				(width 0.1)
				(type default)
			)
			(layer "B.Fab")
		)
		(fp_line
			(start 0.12065 -0.2794)
			(end -0.12065 -0.2794)
			(stroke
				(width 0.1)
				(type default)
			)
			(layer "B.Fab")
		)
		(fp_line
			(start 0.12065 -0.305054)
			(end 0.12065 -0.2794)
			(stroke
				(width 0.1)
				(type default)
			)
			(layer "B.Fab")
		)
		(fp_line
			(start -0.120396 0.3048)
			(end -0.120396 0.2794)
			(stroke
				(width 0.1)
				(type default)
			)
			(layer "B.Fab")
		)
		(fp_line
			(start -0.120396 0.2794)
			(end 0.12065 0.2794)
			(stroke
				(width 0.1)
				(type default)
			)
			(layer "B.Fab")
		)
		(fp_line
			(start -0.12065 -0.2794)
			(end -0.12065 -0.3048)
			(stroke
				(width 0.1)
				(type default)
			)
			(layer "B.Fab")
		)
		(fp_line
			(start -0.12065 -0.3048)
			(end -0.67945 -0.3048)
			(stroke
				(width 0.1)
				(type default)
			)
			(layer "B.Fab")
		)
		(fp_line
			(start -0.67945 0.3048)
			(end -0.120396 0.3048)
			(stroke
				(width 0.1)
				(type default)
			)
			(layer "B.Fab")
		)
		(fp_line
			(start -0.67945 -0.3048)
			(end -0.67945 0.3048)
			(stroke
				(width 0.1)
				(type default)
			)
			(layer "B.Fab")
		)
		(pad "1" smd circle
			(at 0.40005 0)
			(size 0 0)
			(layers "B.Cu" "B.Mask" "B.Paste")
			(net "PWRGD_CHB_CPU1_DIMM1")
		)
		(pad "2" smd circle
			(at -0.40005 0)
			(size 0 0)
			(layers "B.Cu" "B.Mask" "B.Paste")
			(net "PWRGD_FAIL_CPU1_AB")
		)
	)
	(footprint ""
		(layer "B.Cu")
		(at 105.984294 -237.794292 -90)
		(property "Reference" "C1391"
			(at 0 0 90)
			(layer "B.SilkS")
			(hide yes)
			(effects
				(font
					(size 1.27 1.27)
				)
				(justify mirror)
			)
		)
		(property "Value" ""
			(at 0 0 90)
			(layer "B.Fab")
			(effects
				(font
					(size 1.27 1.27)
				)
				(justify mirror)
			)
		)
		(duplicate_pad_numbers_are_jumpers no)
		(fp_line
			(start -1.2954 0.5842)
			(end 1.2954 0.5842)
			(stroke
				(width 0.1524)
				(type default)
			)
			(layer "B.SilkS")
		)
		(fp_line
			(start 1.2954 0.5842)
			(end 1.2954 -0.5842)
			(stroke
				(width 0.1524)
				(type default)
			)
			(layer "B.SilkS")
		)
		(fp_line
			(start -1.2954 -0.5842)
			(end -1.2954 0.5842)
			(stroke
				(width 0.1524)
				(type default)
			)
			(layer "B.SilkS")
		)
		(fp_line
			(start 0 -0.5842)
			(end 0 0.5842)
			(stroke
				(width 0.1524)
				(type default)
			)
			(layer "B.SilkS")
		)
		(fp_line
			(start 1.2954 -0.5842)
			(end -1.2954 -0.5842)
			(stroke
				(width 0.1524)
				(type default)
			)
			(layer "B.SilkS")
		)
		(fp_line
			(start -0.8636 0.4572)
			(end 0.8636 0.4572)
			(stroke
				(width 0.1)
				(type default)
			)
			(layer "B.Fab")
		)
		(fp_line
			(start 0.8636 0.4572)
			(end 0.8636 0.4064)
			(stroke
				(width 0.1)
				(type default)
			)
			(layer "B.Fab")
		)
		(fp_line
			(start -1.1938 0.4064)
			(end -0.8636 0.4064)
			(stroke
				(width 0.1)
				(type default)
			)
			(layer "B.Fab")
		)
		(fp_line
			(start -0.8636 0.4064)
			(end -0.8636 0.4572)
			(stroke
				(width 0.1)
				(type default)
			)
			(layer "B.Fab")
		)
		(fp_line
			(start 0.8636 0.4064)
			(end 1.1938 0.4064)
			(stroke
				(width 0.1)
				(type default)
			)
			(layer "B.Fab")
		)
		(fp_line
			(start 1.1938 0.4064)
			(end 1.1938 -0.4064)
			(stroke
				(width 0.1)
				(type default)
			)
			(layer "B.Fab")
		)
		(fp_line
			(start -1.1938 -0.4064)
			(end -1.1938 0.4064)
			(stroke
				(width 0.1)
				(type default)
			)
			(layer "B.Fab")
		)
		(fp_line
			(start -0.8636 -0.4064)
			(end -1.1938 -0.4064)
			(stroke
				(width 0.1)
				(type default)
			)
			(layer "B.Fab")
		)
		(fp_line
			(start 0.8636 -0.4064)
			(end 0.8636 -0.4572)
			(stroke
				(width 0.1)
				(type default)
			)
			(layer "B.Fab")
		)
		(fp_line
			(start 1.1938 -0.4064)
			(end 0.8636 -0.4064)
			(stroke
				(width 0.1)
				(type default)
			)
			(layer "B.Fab")
		)
		(fp_line
			(start -0.8636 -0.4572)
			(end -0.8636 -0.4064)
			(stroke
				(width 0.1)
				(type default)
			)
			(layer "B.Fab")
		)
		(fp_line
			(start 0.8636 -0.4572)
			(end -0.8636 -0.4572)
			(stroke
				(width 0.1)
				(type default)
			)
			(layer "B.Fab")
		)
		(pad "1" smd rect
			(at 0.7366 0 180)
			(size 0.7112 0.8128)
			(layers "B.Cu" "B.Mask" "B.Paste")
			(net "PVNN_MAIN_CPU1")
		)
		(pad "2" smd rect
			(at -0.7366 0 180)
			(size 0.7112 0.8128)
			(layers "B.Cu" "B.Mask" "B.Paste")
			(net "GND")
		)
	)
)
